FILE_TYPE = MULTI_PHYS_TABLE;

PART 'SN74AVC2T245RSWR'

{========================================================================================}
:VALUE              | PART_TYPE | MATERIAL | PART_NUMBER    = STANDARD | LIFECYCLE | PART_NUMBER   | JEDEC_TYPE           | DESCRIPTION                             | MANUFTR | MANUF_PN           | RD_CMPLS_LVL | CMPLS_LVL | FROM_PJ       | CLASS | DIP_SMD | DATA                       | EE_CHECK_LIST | FP_ECN | PSL | CREATOR | STATUS | MSD | ESD_CDM | ESD_HBM | ESD_MM | PIN_LENGTH_SHORT_PIN | PIN_LENGTH_LONG_PIN | CREATEDAY  ;
{========================================================================================}
 'SN74AVC2T245RSWR' | 'SMLF'    | 'IC'     | 'AL02T245000'(!) = 'End of Design'  | 'Comp-Approve'   | 'AL02T245000' |'UQFN10_0-4_1-8X1-4'| 'IC OTHER (10P) SN74AVC2T245RSWR(UQFN)' | 'TIC'   | 'SN74AVC2T245RSWR' | 'EP(V1)'     | 'EP(V1)'  | 'T6MB-JOSEPH' | 'IC'  | ''      | 'TIC_SN74AVC2T245RSWR.pdf' | ''            | ''     | ''  | ''      | ''     | ''  | ''      | ''      | ''     | ''                   | ''                  | '20160729'
 'SN74AVC2T245RSWR' | 'SMLF'    | 'EMPTY'  | 'AL02T245000'(!) = 'End of Design'  | 'Comp-Approve'   | 'AL02T245000' |'UQFN10_0-4_1-8X1-4'| 'IC OTHER (10P) SN74AVC2T245RSWR(UQFN)' | 'TIC'   | 'SN74AVC2T245RSWR' | 'EP(V1)'     | 'EP(V1)'  | 'T6MB-JOSEPH' | 'IC'  | ''      | 'TIC_SN74AVC2T245RSWR.pdf' | ''            | ''     | ''  | ''      | ''     | ''  | ''      | ''      | ''     | ''                   | ''                  | '20160729'

END_PART

END.

